(kicad_pcb
	(version 20221018)
	(generator pcbnew)
	(general
    (thickness 1.7403)
  )
	(paper "A4")
	(title_block
    (title "Data Center RDIMM DDR4 Tester")
    (date "2024-09-30")
    (rev "1.2.4")
		(comment 9 "footprints 653-661 of 690")
	)
	(layers
    (0 "F.Cu" signal)
    (1 "In1.Cu" power)
    (2 "In2.Cu" signal)
    (3 "In3.Cu" power)
    (4 "In4.Cu" power)
    (5 "In5.Cu" signal)
    (6 "In6.Cu" power)
    (7 "In7.Cu" signal)
    (8 "In8.Cu" power)
    (9 "In9.Cu" signal)
    (10 "In10.Cu" power)
    (31 "B.Cu" signal)
    (32 "B.Adhes" user "B.Adhesive")
    (33 "F.Adhes" user "F.Adhesive")
    (34 "B.Paste" user)
    (35 "F.Paste" user)
    (36 "B.SilkS" user "B.Silkscreen")
    (37 "F.SilkS" user "F.Silkscreen")
    (38 "B.Mask" user)
    (39 "F.Mask" user)
    (40 "Dwgs.User" user "User.Drawings")
    (41 "Cmts.User" user "User.Comments")
    (42 "Eco1.User" user "User.Eco1")
    (43 "Eco2.User" user "User.Eco2")
    (44 "Edge.Cuts" user)
    (45 "Margin" user)
    (46 "B.CrtYd" user "B.Courtyard")
    (47 "F.CrtYd" user "F.Courtyard")
    (48 "B.Fab" user)
    (49 "F.Fab" user)
  )
	(footprint "data-center-rdimm-ddr4-tester-footprints:C_0201" (layer "B.Cu")
    (at 176 95.075 90)
    (descr "Capacitor SMD 0201")
    (tags "capacitor SMD 0201")
    (property "Author" "Antmicro")
    (property "Dielectric" "")
    (property "License" "Apache-2.0")
    (property "MPN" "CC0201KRX6S5BB104")
    (property "Manufacturer" "Yaego")
    (property "Sheetfile" "fpga-power.kicad_sch")
    (property "Sheetname" "FPGA power")
    (property "Val" "100n")
    (property "Voltage" "")
    (property "ki_description" " ")
    (attr smd)
    (fp_text reference "C88" (at 1.045 1.25 270) (layer "B.SilkS")
        (effects (font (size 0.7 0.7) (thickness 0.15)) (justify left bottom mirror))
    )
    (fp_text value "C_100n_0201" (at 0 -1.4 270) (layer "B.Fab") hide
        (effects (font (size 0.7 0.7) (thickness 0.15)) (justify left bottom mirror))
    )
    (fp_text user "License: Apache-2.0" (at -0.72 -4.4 270) (layer "B.Fab") hide
        (effects (font (size 0.7 0.7) (thickness 0.15)) (justify left bottom mirror))
    )
    (fp_text user "Author: Antmicro" (at -0.72 -5.4 270) (layer "B.Fab") hide
        (effects (font (size 0.7 0.7) (thickness 0.15)) (justify left bottom mirror))
    )
    (fp_text user "${REFERENCE}" (at -0.72 -3.4 270) (layer "B.Fab") hide
        (effects (font (size 0.7 0.7) (thickness 0.15)) (justify left bottom mirror))
    )
    (fp_rect (start -0.72 0.38) (end 0.72 -0.38)
      (stroke (width 0.05) (type solid)) (fill none) (layer "B.CrtYd"))
    (fp_rect (start 0.3 -0.15) (end -0.301 0.149)
      (stroke (width 0.15) (type solid)) (fill none) (layer "B.Fab"))
    (pad "" smd roundrect (at -0.349 0.002 90) (size 0.318 0.36) (layers "B.Paste") (roundrect_rratio 0.25))
    (pad "" smd roundrect (at 0.341 0.002 90) (size 0.318 0.36) (layers "B.Paste") (roundrect_rratio 0.25))
    (pad "1" smd roundrect (at -0.321 0.002 90) (size 0.46 0.4) (layers "B.Cu" "B.Mask") (roundrect_rratio 0.25)
      (net 143 "3V3_SYS") (pintype "passive"))
    (pad "2" smd roundrect (at 0.32 0.002 90) (size 0.46 0.4) (layers "B.Cu" "B.Mask") (roundrect_rratio 0.25)
      (net 9 "GND") (pintype "passive"))
  )
	(footprint "data-center-rdimm-ddr4-tester-footprints:C_0402_1005Metric" (layer "B.Cu")
    (at 247.173 47.676)
    (descr "Capacitor SMD 0402")
    (tags "capacitor SMD 0402")
    (property "Author" "Antmicro")
    (property "Dielectric" "X5R")
    (property "License" "Apache-2.0")
    (property "MPN" "GRM155R61H104KE14D")
    (property "Manufacturer" "Murata")
    (property "Sheetfile" "fpga-power.kicad_sch")
    (property "Sheetname" "FPGA power")
    (property "Val" "100n")
    (property "Voltage" "50V")
    (property "ki_description" " ")
    (attr smd)
    (fp_text reference "C313" (at 1.407 1.394 180) (layer "B.SilkS")
        (effects (font (size 0.7 0.7) (thickness 0.15)) (justify left bottom mirror))
    )
    (fp_text value "C_100n_0402" (at 0 -1.4 180) (layer "B.Fab") hide
        (effects (font (size 0.7 0.7) (thickness 0.15)) (justify left bottom mirror))
    )
    (fp_text user "License: Apache-2.0" (at -0.932 -5.17 180) (layer "B.Fab") hide
        (effects (font (size 0.7 0.7) (thickness 0.15)) (justify left bottom mirror))
    )
    (fp_text user "${REFERENCE}" (at -0.932 -3.168 180) (layer "B.Fab") hide
        (effects (font (size 0.7 0.7) (thickness 0.15)) (justify left bottom mirror))
    )
    (fp_text user "Author: Antmicro" (at -0.932 -4.17 180) (layer "B.Fab") hide
        (effects (font (size 0.7 0.7) (thickness 0.15)) (justify left bottom mirror))
    )
    (fp_rect (start -0.94 0.47) (end 0.94 -0.47)
      (stroke (width 0.05) (type solid)) (fill none) (layer "B.CrtYd"))
    (fp_rect (start -0.499 0.249) (end 0.499 -0.249)
      (stroke (width 0.15) (type solid)) (fill none) (layer "B.Fab"))
    (pad "1" smd roundrect (at -0.484 0) (size 0.59 0.64) (layers "B.Cu" "B.Paste" "B.Mask") (roundrect_rratio 0.25)
      (net 77 "VDDQ") (pintype "passive"))
    (pad "2" smd roundrect (at 0.484 0) (size 0.59 0.64) (layers "B.Cu" "B.Paste" "B.Mask") (roundrect_rratio 0.25)
      (net 9 "GND") (pintype "passive"))
  )
	(footprint "data-center-rdimm-ddr4-tester-footprints:C_0201" (layer "B.Cu")
    (at 189.7 78.7)
    (descr "Capacitor SMD 0201")
    (tags "capacitor SMD 0201")
    (property "Author" "Antmicro")
    (property "Dielectric" "")
    (property "License" "Apache-2.0")
    (property "MPN" "CC0201KRX6S5BB104")
    (property "Manufacturer" "Yaego")
    (property "Sheetfile" "fpga-power.kicad_sch")
    (property "Sheetname" "FPGA power")
    (property "Val" "100n")
    (property "Voltage" "")
    (property "ki_description" " ")
    (attr smd)
    (fp_text reference "C296" (at 1.26 -0.48 180) (layer "B.SilkS")
        (effects (font (size 0.7 0.7) (thickness 0.15)) (justify left bottom mirror))
    )
    (fp_text value "C_100n_0201" (at 0 -1.4 180) (layer "B.Fab") hide
        (effects (font (size 0.7 0.7) (thickness 0.15)) (justify left bottom mirror))
    )
    (fp_text user "License: Apache-2.0" (at -0.72 -4.4 180) (layer "B.Fab") hide
        (effects (font (size 0.7 0.7) (thickness 0.15)) (justify left bottom mirror))
    )
    (fp_text user "Author: Antmicro" (at -0.72 -5.4 180) (layer "B.Fab") hide
        (effects (font (size 0.7 0.7) (thickness 0.15)) (justify left bottom mirror))
    )
    (fp_text user "${REFERENCE}" (at -0.72 -3.4 180) (layer "B.Fab") hide
        (effects (font (size 0.7 0.7) (thickness 0.15)) (justify left bottom mirror))
    )
    (fp_rect (start -0.72 0.38) (end 0.72 -0.38)
      (stroke (width 0.05) (type solid)) (fill none) (layer "B.CrtYd"))
    (fp_rect (start 0.3 -0.15) (end -0.301 0.149)
      (stroke (width 0.15) (type solid)) (fill none) (layer "B.Fab"))
    (pad "" smd roundrect (at -0.349 0.002) (size 0.318 0.36) (layers "B.Paste") (roundrect_rratio 0.25))
    (pad "" smd roundrect (at 0.341 0.002) (size 0.318 0.36) (layers "B.Paste") (roundrect_rratio 0.25))
    (pad "1" smd roundrect (at -0.321 0.002) (size 0.46 0.4) (layers "B.Cu" "B.Mask") (roundrect_rratio 0.25)
      (net 77 "VDDQ") (pintype "passive"))
    (pad "2" smd roundrect (at 0.32 0.002) (size 0.46 0.4) (layers "B.Cu" "B.Mask") (roundrect_rratio 0.25)
      (net 9 "GND") (pintype "passive"))
  )
	(footprint "data-center-rdimm-ddr4-tester-footprints:R_0603_1608Metric" (layer "B.Cu")
    (at 136.35 79.55 180)
    (descr "Resistor SMD 0603")
    (tags "resistor SMD 0603")
    (property "Author" "Antmicro")
    (property "License" "Apache-2.0")
    (property "MPN" "ERJ-UP3F3300V")
    (property "Manufacturer" "Panasonic")
    (property "Sheetfile" "supply.kicad_sch")
    (property "Sheetname" "Supply")
    (property "Tolerance" "1%")
    (property "Val" "330R")
    (property "ki_description" "330R resistor in 0603 package with 1% tolerance")
    (attr smd)
    (fp_text reference "R17" (at -0.98 0.79) (layer "B.SilkS")
        (effects (font (size 0.7 0.7) (thickness 0.15)) (justify left bottom mirror))
    )
    (fp_text value "R_330R_0.25W_0603" (at 0 -1.6) (layer "B.Fab") hide
        (effects (font (size 0.7 0.7) (thickness 0.15)) (justify left bottom mirror))
    )
    (fp_text user "${REFERENCE}" (at -1.25 -3.898) (layer "B.Fab") hide
        (effects (font (size 0.7 0.7) (thickness 0.15)) (justify left bottom mirror))
    )
    (fp_text user "License: Apache-2.0" (at -1.25 -5.9) (layer "B.Fab") hide
        (effects (font (size 0.7 0.7) (thickness 0.15)) (justify left bottom mirror))
    )
    (fp_text user "Author: Antmicro" (at -1.25 -4.9) (layer "B.Fab") hide
        (effects (font (size 0.7 0.7) (thickness 0.15)) (justify left bottom mirror))
    )
    (fp_line (start -0.3 -0.3) (end 0.3 -0.3)
      (stroke (width 0.15) (type solid)) (layer "B.SilkS"))
    (fp_line (start -0.3 0.3) (end 0.3 0.3)
      (stroke (width 0.15) (type solid)) (layer "B.SilkS"))
    (fp_rect (start -1.25 0.7) (end 1.25 -0.7)
      (stroke (width 0.05) (type solid)) (fill none) (layer "B.CrtYd"))
    (fp_rect (start -0.8 0.4) (end 0.8 -0.4)
      (stroke (width 0.15) (type solid)) (fill none) (layer "B.Fab"))
    (pad "1" smd roundrect (at -0.7 0 180) (size 0.6 0.8) (layers "B.Cu" "B.Paste" "B.Mask") (roundrect_rratio 0.2)
      (net 854 "Net-(R17-Pad1)") (pintype "passive"))
    (pad "2" smd roundrect (at 0.7 0 180) (size 0.6 0.8) (layers "B.Cu" "B.Paste" "B.Mask") (roundrect_rratio 0.2)
      (net 144 "1V8_SYS") (pintype "passive"))
  )
	(footprint "data-center-rdimm-ddr4-tester-footprints:C_1206_3216Metric" (layer "B.Cu")
    (at 193.5 111.7 180)
    (descr "Capacitor SMD 1206")
    (tags "capacitor SMD 1206")
    (property "Author" "Antmicro")
    (property "Dielectric" "")
    (property "License" "Apache-2.0")
    (property "MPN" "C3216X5R1C476M160AB")
    (property "Manufacturer" "TDK")
    (property "Sheetfile" "ethernet.kicad_sch")
    (property "Sheetname" "Ethernet")
    (property "Val" "47u/16V")
    (property "Voltage" "")
    (property "ki_description" " ")
    (attr smd)
    (fp_text reference "C228" (at -1.38 1.28) (layer "B.SilkS")
        (effects (font (size 0.7 0.7) (thickness 0.15)) (justify left bottom mirror))
    )
    (fp_text value "C_47u_16V_1206" (at 0 -2.1) (layer "B.Fab") hide
        (effects (font (size 0.7 0.7) (thickness 0.15)) (justify left bottom mirror))
    )
    (fp_text user "Author: Antmicro" (at -2.8 -5.6) (layer "B.Fab") hide
        (effects (font (size 0.7 0.7) (thickness 0.15)) (justify left bottom mirror))
    )
    (fp_text user "License: Apache-2.0" (at -2.8 -6.6) (layer "B.Fab") hide
        (effects (font (size 0.7 0.7) (thickness 0.15)) (justify left bottom mirror))
    )
    (fp_text user "${REFERENCE}" (at -2.8 -4.6) (layer "B.Fab") hide
        (effects (font (size 0.7 0.7) (thickness 0.15)) (justify left bottom mirror))
    )
    (fp_line (start -2.625 0.3) (end -2.625 -0.3)
      (stroke (width 0.15) (type solid)) (layer "B.SilkS"))
    (fp_line (start 0.5 -0.9) (end -0.5 -0.9)
      (stroke (width 0.15) (type solid)) (layer "B.SilkS"))
    (fp_line (start 0.5 0.9) (end -0.5 0.9)
      (stroke (width 0.15) (type solid)) (layer "B.SilkS"))
    (fp_line (start 2.625 0.3) (end 2.625 -0.3)
      (stroke (width 0.15) (type solid)) (layer "B.SilkS"))
    (fp_rect (start -2.8 1.15) (end 2.8 -1.15)
      (stroke (width 0.05) (type solid)) (fill none) (layer "B.CrtYd"))
    (fp_rect (start -1.6 0.8) (end 1.6 -0.8)
      (stroke (width 0.15) (type solid)) (fill none) (layer "B.Fab"))
    (pad "1" smd rect (at -1.8 0 180) (size 1.5 1.8) (layers "B.Cu" "B.Paste" "B.Mask")
      (net 864 "VIN_POE") (pintype "passive"))
    (pad "2" smd rect (at 1.8 0 180) (size 1.5 1.8) (layers "B.Cu" "B.Paste" "B.Mask")
      (net 9 "GND") (pintype "passive"))
  )
	(footprint "data-center-rdimm-ddr4-tester-footprints:R_0402_1005Metric" (layer "B.Cu")
    (at 136.6 109.1 90)
    (descr "Resistor SMD 0402")
    (tags "resistor SMD 0402")
    (property "Author" "Antmicro")
    (property "License" "Apache-2.0")
    (property "MPN" "CR0402-FX-1003GLF")
    (property "Manufacturer" "Bourns")
    (property "Sheetfile" "supply.kicad_sch")
    (property "Sheetname" "Supply")
    (property "Tolerance" "1%")
    (property "Val" "100k")
    (property "ki_description" "100k resistor in 0402 package with 1% tolerance")
    (attr smd)
    (fp_text reference "R124" (at 1.32 1.28 270) (layer "B.SilkS")
        (effects (font (size 0.7 0.7) (thickness 0.15)) (justify left bottom mirror))
    )
    (fp_text value "R_100k_0402" (at 0 -1.4 270) (layer "B.Fab") hide
        (effects (font (size 0.7 0.7) (thickness 0.15)) (justify left bottom mirror))
    )
    (fp_text user "Author: Antmicro" (at -0.95 -4.169 270) (layer "B.Fab") hide
        (effects (font (size 0.7 0.7) (thickness 0.15)) (justify left bottom mirror))
    )
    (fp_text user "${REFERENCE}" (at -0.95 -3.168 270) (layer "B.Fab") hide
        (effects (font (size 0.7 0.7) (thickness 0.15)) (justify left bottom mirror))
    )
    (fp_text user "License: Apache-2.0" (at -0.95 -5.169 270) (layer "B.Fab") hide
        (effects (font (size 0.7 0.7) (thickness 0.15)) (justify left bottom mirror))
    )
    (fp_rect (start -0.93 0.47) (end 0.93 -0.47)
      (stroke (width 0.05) (type solid)) (fill none) (layer "B.CrtYd"))
    (fp_rect (start -0.5 0.25) (end 0.5 -0.25)
      (stroke (width 0.15) (type solid)) (fill none) (layer "B.Fab"))
    (pad "1" smd roundrect (at -0.485 0 90) (size 0.59 0.64) (layers "B.Cu" "B.Paste" "B.Mask") (roundrect_rratio 0.25)
      (net 9 "GND") (pintype "passive"))
    (pad "2" smd roundrect (at 0.485 0 90) (size 0.59 0.64) (layers "B.Cu" "B.Paste" "B.Mask") (roundrect_rratio 0.25)
      (net 804 "FPGA_POWER_CYCLE") (pintype "passive"))
  )
	(footprint "data-center-rdimm-ddr4-tester-footprints:PowerDI5" (layer "B.Cu")
    (at 209.6 132.3 180)
    (property "Author" "Antmicro")
    (property "License" "Apache-2.0")
    (property "MPN" "PDS760-13")
    (property "Manufacturer" "Diodes Incorporated")
    (property "Sheetfile" "fmc_hpc.kicad_sch")
    (property "Sheetname" "FMC HPC")
    (property "ki_description" "PDS760 Series 60 V 7 A Surface Mount Schottky Barrier Rectifier - PowerDI-5")
    (property "ki_keywords" "PDS760 Series 60 V 7 A Surface Mount Schottky Barrier Rectifier - PowerDI-5")
    (attr smd)
    (fp_text reference "D18" (at 2.77 -2.66) (layer "B.SilkS")
        (effects (font (size 0.7 0.7) (thickness 0.15)) (justify left bottom mirror))
    )
    (fp_text value "PDS760" (at 0 -3.4) (layer "B.Fab") hide
        (effects (font (size 0.7 0.7) (thickness 0.15)) (justify right bottom mirror))
    )
    (fp_text user "${REFERENCE}" (at -3.302 -18.527) (layer "B.Fab") hide
        (effects (font (size 0.7 0.7) (thickness 0.15)) (justify left bottom mirror))
    )
    (fp_text user "License: Apache-2.0" (at -3.302 -20.928) (layer "B.Fab") hide
        (effects (font (size 0.7 0.7) (thickness 0.15)) (justify left bottom mirror))
    )
    (fp_text user "Author: Antmicro" (at -3.302 -19.728) (layer "B.Fab") hide
        (effects (font (size 0.7 0.7) (thickness 0.15)) (justify left bottom mirror))
    )
    (fp_line (start -2.7 -2.023) (end -2.7 -1.823)
      (stroke (width 0.12) (type solid)) (layer "B.SilkS"))
    (fp_line (start -2.7 1.8) (end -2.7 2)
      (stroke (width 0.12) (type solid)) (layer "B.SilkS"))
    (fp_line (start -2.7 2) (end 2.7 2)
      (stroke (width 0.12) (type solid)) (layer "B.SilkS"))
    (fp_line (start 2.7 -2.023) (end -2.7 -2.023)
      (stroke (width 0.12) (type solid)) (layer "B.SilkS"))
    (fp_line (start 2.7 -1.823) (end 2.7 -2.023)
      (stroke (width 0.12) (type solid)) (layer "B.SilkS"))
    (fp_line (start 2.7 2) (end 2.7 1.8)
      (stroke (width 0.12) (type solid)) (layer "B.SilkS"))
    (fp_rect (start -3.702 2.3) (end 3.7 -2.3)
      (stroke (width 0.05) (type solid)) (fill none) (layer "B.CrtYd"))
    (pad "A" smd roundrect (at -2.862 -0.941 270) (size 1.39 1.4) (layers "B.Cu" "B.Paste" "B.Mask") (roundrect_rratio 0.25)
      (net 535 "12P0V") (pinfunction "A") (pintype "passive"))
    (pad "A" smd roundrect (at -2.862 0.94 90) (size 1.39 1.4) (layers "B.Cu" "B.Paste" "B.Mask") (roundrect_rratio 0.25)
      (net 535 "12P0V") (pinfunction "A") (pintype "passive"))
    (pad "C" smd roundrect (at 1.1 0 270) (size 3.36 4.86) (layers "B.Cu" "B.Paste" "B.Mask") (roundrect_rratio 0.05)
      (net 103 "VIN") (pinfunction "C") (pintype "passive"))
  )
	(footprint "data-center-rdimm-ddr4-tester-footprints:C_0201" (layer "B.Cu")
    (at 189.59 102.97 -90)
    (descr "Capacitor SMD 0201")
    (tags "capacitor SMD 0201")
    (property "Author" "Antmicro")
    (property "Dielectric" "")
    (property "License" "Apache-2.0")
    (property "MPN" "CC0201KRX6S5BB104")
    (property "Manufacturer" "Yaego")
    (property "Sheetfile" "fpga-power.kicad_sch")
    (property "Sheetname" "FPGA power")
    (property "Val" "100n")
    (property "Voltage" "")
    (property "ki_description" " ")
    (attr smd)
    (fp_text reference "C85" (at 0.45 -0.38 90) (layer "B.SilkS")
        (effects (font (size 0.7 0.7) (thickness 0.15)) (justify left bottom mirror))
    )
    (fp_text value "C_100n_0201" (at 0 -1.4 90) (layer "B.Fab") hide
        (effects (font (size 0.7 0.7) (thickness 0.15)) (justify left bottom mirror))
    )
    (fp_text user "${REFERENCE}" (at -0.72 -3.4 90) (layer "B.Fab") hide
        (effects (font (size 0.7 0.7) (thickness 0.15)) (justify left bottom mirror))
    )
    (fp_text user "License: Apache-2.0" (at -0.72 -4.4 90) (layer "B.Fab") hide
        (effects (font (size 0.7 0.7) (thickness 0.15)) (justify left bottom mirror))
    )
    (fp_text user "Author: Antmicro" (at -0.72 -5.4 90) (layer "B.Fab") hide
        (effects (font (size 0.7 0.7) (thickness 0.15)) (justify left bottom mirror))
    )
    (fp_rect (start -0.72 0.38) (end 0.72 -0.38)
      (stroke (width 0.05) (type solid)) (fill none) (layer "B.CrtYd"))
    (fp_rect (start 0.3 -0.15) (end -0.301 0.149)
      (stroke (width 0.15) (type solid)) (fill none) (layer "B.Fab"))
    (pad "" smd roundrect (at -0.349 0.002 270) (size 0.318 0.36) (layers "B.Paste") (roundrect_rratio 0.25))
    (pad "" smd roundrect (at 0.341 0.002 270) (size 0.318 0.36) (layers "B.Paste") (roundrect_rratio 0.25))
    (pad "1" smd roundrect (at -0.321 0.002 270) (size 0.46 0.4) (layers "B.Cu" "B.Mask") (roundrect_rratio 0.25)
      (net 143 "3V3_SYS") (pintype "passive"))
    (pad "2" smd roundrect (at 0.32 0.002 270) (size 0.46 0.4) (layers "B.Cu" "B.Mask") (roundrect_rratio 0.25)
      (net 9 "GND") (pintype "passive"))
  )
	(footprint "data-center-rdimm-ddr4-tester-footprints:C_0402_1005Metric" (layer "B.Cu")
    (at 125.8 88.1 180)
    (descr "Capacitor SMD 0402")
    (tags "capacitor SMD 0402")
    (property "Author" "Antmicro")
    (property "Dielectric" "X5R")
    (property "License" "Apache-2.0")
    (property "MPN" "GRM155R61H104KE14D")
    (property "Manufacturer" "Murata")
    (property "Sheetfile" "supply.kicad_sch")
    (property "Sheetname" "Supply")
    (property "Val" "100n")
    (property "Voltage" "50V")
    (property "ki_description" " ")
    (attr smd)
    (fp_text reference "C235" (at -1.31 0.61) (layer "B.SilkS")
        (effects (font (size 0.7 0.7) (thickness 0.15)) (justify left bottom mirror))
    )
    (fp_text value "C_100n_0402" (at 0 -1.4) (layer "B.Fab") hide
        (effects (font (size 0.7 0.7) (thickness 0.15)) (justify left bottom mirror))
    )
    (fp_text user "${REFERENCE}" (at -0.932 -3.168) (layer "B.Fab") hide
        (effects (font (size 0.7 0.7) (thickness 0.15)) (justify left bottom mirror))
    )
    (fp_text user "Author: Antmicro" (at -0.932 -4.17) (layer "B.Fab") hide
        (effects (font (size 0.7 0.7) (thickness 0.15)) (justify left bottom mirror))
    )
    (fp_text user "License: Apache-2.0" (at -0.932 -5.17) (layer "B.Fab") hide
        (effects (font (size 0.7 0.7) (thickness 0.15)) (justify left bottom mirror))
    )
    (fp_rect (start -0.94 0.47) (end 0.94 -0.47)
      (stroke (width 0.05) (type solid)) (fill none) (layer "B.CrtYd"))
    (fp_rect (start -0.499 0.249) (end 0.499 -0.249)
      (stroke (width 0.15) (type solid)) (fill none) (layer "B.Fab"))
    (pad "1" smd roundrect (at -0.484 0 180) (size 0.59 0.64) (layers "B.Cu" "B.Paste" "B.Mask") (roundrect_rratio 0.25)
      (net 143 "3V3_SYS") (pintype "passive"))
    (pad "2" smd roundrect (at 0.484 0 180) (size 0.59 0.64) (layers "B.Cu" "B.Paste" "B.Mask") (roundrect_rratio 0.25)
      (net 9 "GND") (pintype "passive"))
  )
)
